(kicad_pcb
	(version 20260206)
	(generator "pcbnew")
	(generator_version "10.0")
	(general
		(thickness 1.6)
		(legacy_teardrops no)
	)
	(paper "A4")
	(title_block
		(title "timecard-production-celestica-r4006 — R4006-B0001-02_R01.brd")
		(comment 1 "Time Appliance Project (Time Card) / footprints 391-396 of 1113")
	)
	(layers
		(0 "F.Cu" signal "TOP")
		(4 "In1.Cu" signal "L02_GND1")
		(6 "In2.Cu" signal "L03_SIG1")
		(8 "In3.Cu" signal "L04_GND2")
		(10 "In4.Cu" signal "L05_VCC1")
		(12 "In5.Cu" signal "L06_VCC2")
		(14 "In6.Cu" signal "L07_GND3")
		(16 "In7.Cu" signal "L08_SIG2")
		(18 "In8.Cu" signal "L09_GND4")
		(2 "B.Cu" signal "BOTTOM")
		(9 "F.Adhes" user "F.Adhesive")
		(11 "B.Adhes" user "B.Adhesive")
		(13 "F.Paste" user "Package Geometry/Pastemask Top")
		(15 "B.Paste" user "Package Geometry/Pastemask Bottom")
		(5 "F.SilkS" user "Ref Des/Silkscreen Top")
		(7 "B.SilkS" user "Ref Des/Silkscreen Bottom")
		(1 "F.Mask" user "Board Geometry/Soldermask Top")
		(3 "B.Mask" user "Board Geometry/Soldermask Bottom")
		(17 "Dwgs.User" user "User.Drawings")
		(19 "Cmts.User" user "User.Comments")
		(21 "Eco1.User" user "User.Eco1")
		(23 "Eco2.User" user "User.Eco2")
		(25 "Edge.Cuts" user "Board Geometry/Outline")
		(27 "Margin" user)
		(31 "F.CrtYd" user "Package Geometry/Place Bound Top")
		(29 "B.CrtYd" user "Package Geometry/Place Bound Bottom")
		(35 "F.Fab" user "Ref Des/Assembly Top")
		(33 "B.Fab" user "Ref Des/Assembly Bottom")
	)
	(footprint ""
		(layer "F.Cu")
		(at 18.034 -83.947 -90)
		(property "Reference" "TP4"
			(at 0 0 270)
			(layer "F.SilkS")
			(hide yes)
			(effects
				(font
					(size 1.27 1.27)
				)
			)
		)
		(property "Value" ""
			(at 0 0 270)
			(layer "F.Fab")
			(effects
				(font
					(size 1.27 1.27)
				)
			)
		)
		(property "Device Type" "TP_PIONT-TP010CT020B030_PTH-TPA"
			(at -1.341882 0.996696 270)
			(unlocked yes)
			(layer "F.Fab")
			(hide yes)
			(effects
				(font
					(size 0.7874 0.5842)
					(thickness 0.1524)
				)
				(justify left)
			)
		)
		(duplicate_pad_numbers_are_jumpers no)
		(fp_poly
			(pts
				(arc
					(start 0 -0.889)
					(mid 0 0.889)
					(end 0 -0.889)
				)
			)
			(stroke
				(width 0)
				(type default)
			)
			(fill no)
			(layer "B.CrtYd")
		)
		(fp_poly
			(pts
				(arc
					(start 0 -0.889)
					(mid 0 0.889)
					(end 0 -0.889)
				)
			)
			(stroke
				(width 0)
				(type default)
			)
			(fill no)
			(layer "F.CrtYd")
		)
		(pad "1" thru_hole circle
			(at 0 0 270)
			(size 0.508 0.508)
			(drill 0.254)
			(layers "*.Cu" "*.Mask")
			(remove_unused_layers no)
			(net "XP5R0V_FT4232")
			(clearance 0.1016)
			(padstack
				(mode front_inner_back)
				(layer "Inner"
					(shape circle)
					(size 0.508 0.508)
					(clearance 0.1016)
				)
				(layer "B.Cu"
					(shape circle)
					(size 0.762 0.762)
					(clearance -0.0254)
				)
			)
		)
	)
	(footprint ""
		(layer "F.Cu")
		(at 25.273 -93.98)
		(property "Reference" "TP11"
			(at -0.08763 -0.8128 90)
			(unlocked yes)
			(layer "F.SilkS")
			(effects
				(font
					(size 0.7874 0.5842)
					(thickness 0.1524)
				)
				(justify left)
			)
		)
		(property "Value" ""
			(at 0 0 0)
			(layer "F.Fab")
			(effects
				(font
					(size 1.27 1.27)
				)
			)
		)
		(property "Device Type" "TP_PIONT-TP010CT020B030_PTH-TPA"
			(at -1.341882 0.996696 0)
			(unlocked yes)
			(layer "F.Fab")
			(hide yes)
			(effects
				(font
					(size 0.7874 0.5842)
					(thickness 0.000001)
				)
				(justify left)
			)
		)
		(duplicate_pad_numbers_are_jumpers no)
		(fp_poly
			(pts
				(arc
					(start 0.889 0)
					(mid -0.889 0)
					(end 0.889 0)
				)
			)
			(stroke
				(width 0)
				(type default)
			)
			(fill no)
			(layer "B.CrtYd")
		)
		(fp_poly
			(pts
				(arc
					(start 0.889 0)
					(mid -0.889 0)
					(end 0.889 0)
				)
			)
			(stroke
				(width 0)
				(type default)
			)
			(fill no)
			(layer "F.CrtYd")
		)
		(pad "1" thru_hole circle
			(at 0 0)
			(size 0.508 0.508)
			(drill 0.254)
			(layers "*.Cu" "*.Mask")
			(remove_unused_layers no)
			(net "FT_USB_DETECT")
			(clearance 0.1016)
			(padstack
				(mode front_inner_back)
				(layer "Inner"
					(shape circle)
					(size 0.508 0.508)
					(clearance 0.1016)
				)
				(layer "B.Cu"
					(shape circle)
					(size 0.762 0.762)
					(clearance -0.0254)
				)
			)
		)
	)
	(footprint ""
		(layer "F.Cu")
		(at 145.8214 -88.0618 180)
		(property "Reference" "R4"
			(at 0.2794 -7.71017 0)
			(unlocked yes)
			(layer "F.SilkS")
			(effects
				(font
					(size 0.7874 0.5842)
					(thickness 0.1524)
				)
			)
		)
		(property "Value" "VAL*"
			(at 0.02032 2.13233 180)
			(unlocked yes)
			(layer "F.Fab")
			(hide yes)
			(effects
				(font
					(size 0.7874 0.5842)
					(thickness 0.1524)
				)
			)
		)
		(property "Device Type" "RESISTOR-G155-11002-01,10KOHM,A"
			(at 0.008382 1.210564 180)
			(unlocked yes)
			(layer "F.Fab")
			(hide yes)
			(effects
				(font
					(size 0.7874 0.5842)
					(thickness 0.1524)
				)
			)
		)
		(property "User Part Number" "PARTNUM*"
			(at 0.02032 4.024884 180)
			(unlocked yes)
			(layer "Cmts.User")
			(hide yes)
			(effects
				(font
					(size 0.7874 0.5842)
					(thickness 0.1524)
				)
			)
		)
		(property "Tolerance" "TOL*"
			(at 0.044704 3.05435 180)
			(unlocked yes)
			(layer "Cmts.User")
			(hide yes)
			(effects
				(font
					(size 0.7874 0.5842)
					(thickness 0.1524)
				)
			)
		)
		(duplicate_pad_numbers_are_jumpers no)
		(fp_line
			(start 1.143 0.5588)
			(end 1.143 -0.5588)
			(stroke
				(width 0.1)
				(type default)
			)
			(layer "F.SilkS")
		)
		(fp_line
			(start 1.143 -0.5588)
			(end -1.143 -0.5588)
			(stroke
				(width 0.1)
				(type default)
			)
			(layer "F.SilkS")
		)
		(fp_line
			(start -1.143 0.5588)
			(end 1.143 0.5588)
			(stroke
				(width 0.1)
				(type default)
			)
			(layer "F.SilkS")
		)
		(fp_line
			(start -1.143 -0.5588)
			(end -1.143 0.5588)
			(stroke
				(width 0.1)
				(type default)
			)
			(layer "F.SilkS")
		)
		(fp_rect
			(start 1.143 0.5588)
			(end -1.143 -0.5588)
			(stroke
				(width 0)
				(type default)
			)
			(fill no)
			(layer "F.CrtYd")
		)
		(fp_line
			(start 0.508 0.3048)
			(end 0.508 -0.3048)
			(stroke
				(width 0.1)
				(type default)
			)
			(layer "F.Fab")
		)
		(fp_line
			(start 0.508 -0.3048)
			(end -0.508 -0.3048)
			(stroke
				(width 0.1)
				(type default)
			)
			(layer "F.Fab")
		)
		(fp_line
			(start -0.508 0.3048)
			(end 0.508 0.3048)
			(stroke
				(width 0.1)
				(type default)
			)
			(layer "F.Fab")
		)
		(fp_line
			(start -0.508 -0.3048)
			(end -0.508 0.3048)
			(stroke
				(width 0.1)
				(type default)
			)
			(layer "F.Fab")
		)
		(pad "1" smd rect
			(at -0.5334 0 180)
			(size 0.7112 0.6096)
			(layers "F.Cu" "F.Mask" "F.Paste")
			(net "XP12R0V_IN")
		)
		(pad "2" smd rect
			(at 0.5334 0 180)
			(size 0.7112 0.6096)
			(layers "F.Cu" "F.Mask" "F.Paste")
			(net "XP12R0V_A_EN")
		)
		(zone
			(layer "F.Cu")
			(hatch none 0.5)
			(connect_pads
				(clearance 0)
			)
			(min_thickness 0.25)
			(keepout
				(tracks allowed)
				(vias not_allowed)
				(pads allowed)
				(copperpour not_allowed)
				(footprints allowed)
			)
			(placement
				(enabled no)
				(sheetname "")
			)
			(fill
				(thermal_gap 0.5)
				(thermal_bridge_width 0.5)
				(island_removal_mode 0)
			)
			(polygon
				(pts
					(xy 145.7452 -88.3666) (xy 145.7452 -87.757) (xy 145.8976 -87.757) (xy 145.8976 -88.3666)
				)
			)
		)
	)
	(footprint ""
		(layer "F.Cu")
		(at 81.0006 -49.911 180)
		(property "Reference" "R86"
			(at 1.016 -14.64437 0)
			(unlocked yes)
			(layer "F.SilkS")
			(effects
				(font
					(size 0.7874 0.5842)
					(thickness 0.1524)
				)
			)
		)
		(property "Value" "VAL*"
			(at 0.02032 2.13233 180)
			(unlocked yes)
			(layer "F.Fab")
			(hide yes)
			(effects
				(font
					(size 0.7874 0.5842)
					(thickness 0.1524)
				)
			)
		)
		(property "Tolerance" "TOL*"
			(at 0.044704 3.05435 180)
			(unlocked yes)
			(layer "Cmts.User")
			(hide yes)
			(effects
				(font
					(size 0.7874 0.5842)
					(thickness 0.1524)
				)
			)
		)
		(property "User Part Number" "PARTNUM*"
			(at 0.02032 4.024884 180)
			(unlocked yes)
			(layer "Cmts.User")
			(hide yes)
			(effects
				(font
					(size 0.7874 0.5842)
					(thickness 0.1524)
				)
			)
		)
		(property "Device Type" "RESISTOR-G155-100R0-J0,0OHM,-"
			(at 0.008382 1.210564 180)
			(unlocked yes)
			(layer "F.Fab")
			(hide yes)
			(effects
				(font
					(size 0.7874 0.5842)
					(thickness 0.1524)
				)
			)
		)
		(duplicate_pad_numbers_are_jumpers no)
		(fp_line
			(start 1.143 0.5588)
			(end 1.143 -0.5588)
			(stroke
				(width 0.1)
				(type default)
			)
			(layer "F.SilkS")
		)
		(fp_line
			(start 1.143 -0.5588)
			(end -1.143 -0.5588)
			(stroke
				(width 0.1)
				(type default)
			)
			(layer "F.SilkS")
		)
		(fp_line
			(start -1.143 0.5588)
			(end 1.143 0.5588)
			(stroke
				(width 0.1)
				(type default)
			)
			(layer "F.SilkS")
		)
		(fp_line
			(start -1.143 -0.5588)
			(end -1.143 0.5588)
			(stroke
				(width 0.1)
				(type default)
			)
			(layer "F.SilkS")
		)
		(fp_rect
			(start 1.143 -0.5588)
			(end -1.143 0.5588)
			(stroke
				(width 0)
				(type default)
			)
			(fill no)
			(layer "F.CrtYd")
		)
		(fp_line
			(start 0.508 0.3048)
			(end 0.508 -0.3048)
			(stroke
				(width 0.1)
				(type default)
			)
			(layer "F.Fab")
		)
		(fp_line
			(start 0.508 -0.3048)
			(end -0.508 -0.3048)
			(stroke
				(width 0.1)
				(type default)
			)
			(layer "F.Fab")
		)
		(fp_line
			(start -0.508 0.3048)
			(end 0.508 0.3048)
			(stroke
				(width 0.1)
				(type default)
			)
			(layer "F.Fab")
		)
		(fp_line
			(start -0.508 -0.3048)
			(end -0.508 0.3048)
			(stroke
				(width 0.1)
				(type default)
			)
			(layer "F.Fab")
		)
		(pad "1" smd rect
			(at -0.5334 0 180)
			(size 0.7112 0.6096)
			(layers "F.Cu" "F.Mask" "F.Paste")
			(net "FPGA_OUT_MAC_PPS_IN0N")
		)
		(pad "2" smd rect
			(at 0.5334 0 180)
			(size 0.7112 0.6096)
			(layers "F.Cu" "F.Mask" "F.Paste")
			(net "R_MAC_PPS_IN0N")
		)
		(zone
			(layer "F.Cu")
			(hatch none 0.5)
			(connect_pads
				(clearance 0)
			)
			(min_thickness 0.25)
			(keepout
				(tracks allowed)
				(vias not_allowed)
				(pads allowed)
				(copperpour not_allowed)
				(footprints allowed)
			)
			(placement
				(enabled no)
				(sheetname "")
			)
			(fill
				(thermal_gap 0.5)
				(thermal_bridge_width 0.5)
				(island_removal_mode 0)
			)
			(polygon
				(pts
					(xy 80.9244 -49.6062) (xy 81.0768 -49.6062) (xy 81.0768 -50.2158) (xy 80.9244 -50.2158)
				)
			)
		)
	)
	(footprint ""
		(layer "F.Cu")
		(at 150.381462 -58.014108 180)
		(property "Reference" "R297"
			(at 1.410462 3.541522 0)
			(unlocked yes)
			(layer "F.SilkS")
			(effects
				(font
					(size 0.7874 0.5842)
					(thickness 0.1524)
				)
			)
		)
		(property "Value" "VAL*"
			(at 0.02032 2.13233 180)
			(unlocked yes)
			(layer "F.Fab")
			(hide yes)
			(effects
				(font
					(size 0.7874 0.5842)
					(thickness 0.1524)
				)
			)
		)
		(property "Tolerance" "TOL*"
			(at 0.044704 3.05435 180)
			(unlocked yes)
			(layer "Cmts.User")
			(hide yes)
			(effects
				(font
					(size 0.7874 0.5842)
					(thickness 0.1524)
				)
			)
		)
		(property "User Part Number" "PARTNUM*"
			(at 0.02032 4.024884 180)
			(unlocked yes)
			(layer "Cmts.User")
			(hide yes)
			(effects
				(font
					(size 0.7874 0.5842)
					(thickness 0.1524)
				)
			)
		)
		(property "Device Type" "RESISTOR-G155-14701-01,4.7KOHMA"
			(at 0.008382 1.210564 180)
			(unlocked yes)
			(layer "F.Fab")
			(hide yes)
			(effects
				(font
					(size 0.7874 0.5842)
					(thickness 0.1524)
				)
			)
		)
		(duplicate_pad_numbers_are_jumpers no)
		(fp_line
			(start 1.143 0.5588)
			(end 1.143 -0.5588)
			(stroke
				(width 0.1)
				(type default)
			)
			(layer "F.SilkS")
		)
		(fp_line
			(start 1.143 -0.5588)
			(end -1.143 -0.5588)
			(stroke
				(width 0.1)
				(type default)
			)
			(layer "F.SilkS")
		)
		(fp_line
			(start -1.143 0.5588)
			(end 1.143 0.5588)
			(stroke
				(width 0.1)
				(type default)
			)
			(layer "F.SilkS")
		)
		(fp_line
			(start -1.143 -0.5588)
			(end -1.143 0.5588)
			(stroke
				(width 0.1)
				(type default)
			)
			(layer "F.SilkS")
		)
		(fp_rect
			(start -1.143 0.5588)
			(end 1.143 -0.5588)
			(stroke
				(width 0)
				(type default)
			)
			(fill no)
			(layer "F.CrtYd")
		)
		(fp_line
			(start 0.508 0.3048)
			(end 0.508 -0.3048)
			(stroke
				(width 0.1)
				(type default)
			)
			(layer "F.Fab")
		)
		(fp_line
			(start 0.508 -0.3048)
			(end -0.508 -0.3048)
			(stroke
				(width 0.1)
				(type default)
			)
			(layer "F.Fab")
		)
		(fp_line
			(start -0.508 0.3048)
			(end 0.508 0.3048)
			(stroke
				(width 0.1)
				(type default)
			)
			(layer "F.Fab")
		)
		(fp_line
			(start -0.508 -0.3048)
			(end -0.508 0.3048)
			(stroke
				(width 0.1)
				(type default)
			)
			(layer "F.Fab")
		)
		(pad "1" smd rect
			(at -0.5334 0 180)
			(size 0.7112 0.6096)
			(layers "F.Cu" "F.Mask" "F.Paste")
			(net "R_SHT3X_RST_N")
		)
		(pad "2" smd rect
			(at 0.5334 0 180)
			(size 0.7112 0.6096)
			(layers "F.Cu" "F.Mask" "F.Paste")
			(net "SG")
		)
		(zone
			(layer "F.Cu")
			(hatch none 0.5)
			(connect_pads
				(clearance 0)
			)
			(min_thickness 0.25)
			(keepout
				(tracks allowed)
				(vias not_allowed)
				(pads allowed)
				(copperpour not_allowed)
				(footprints allowed)
			)
			(placement
				(enabled no)
				(sheetname "")
			)
			(fill
				(thermal_gap 0.5)
				(thermal_bridge_width 0.5)
				(island_removal_mode 0)
			)
			(polygon
				(pts
					(xy 150.457662 -58.318908) (xy 150.305262 -58.318908) (xy 150.305262 -57.709308) (xy 150.457662 -57.709308)
				)
			)
		)
	)
	(footprint ""
		(layer "F.Cu")
		(at 145.8214 -99.2378 180)
		(property "Reference" "R15"
			(at -3.0226 0.16383 0)
			(unlocked yes)
			(layer "F.SilkS")
			(effects
				(font
					(size 0.7874 0.5842)
					(thickness 0.1524)
				)
			)
		)
		(property "Value" "VAL*"
			(at 0.02032 2.13233 180)
			(unlocked yes)
			(layer "F.Fab")
			(hide yes)
			(effects
				(font
					(size 0.7874 0.5842)
					(thickness 0.1524)
				)
			)
		)
		(property "Device Type" "RESISTOR-G155-11002-01,10KOHM,A"
			(at 0.008382 1.210564 180)
			(unlocked yes)
			(layer "F.Fab")
			(hide yes)
			(effects
				(font
					(size 0.7874 0.5842)
					(thickness 0.1524)
				)
			)
		)
		(property "User Part Number" "PARTNUM*"
			(at 0.02032 4.024884 180)
			(unlocked yes)
			(layer "Cmts.User")
			(hide yes)
			(effects
				(font
					(size 0.7874 0.5842)
					(thickness 0.1524)
				)
			)
		)
		(property "Tolerance" "TOL*"
			(at 0.044704 3.05435 180)
			(unlocked yes)
			(layer "Cmts.User")
			(hide yes)
			(effects
				(font
					(size 0.7874 0.5842)
					(thickness 0.1524)
				)
			)
		)
		(duplicate_pad_numbers_are_jumpers no)
		(fp_line
			(start 1.143 0.5588)
			(end 1.143 -0.5588)
			(stroke
				(width 0.1)
				(type default)
			)
			(layer "F.SilkS")
		)
		(fp_line
			(start 1.143 -0.5588)
			(end -1.143 -0.5588)
			(stroke
				(width 0.1)
				(type default)
			)
			(layer "F.SilkS")
		)
		(fp_line
			(start -1.143 0.5588)
			(end 1.143 0.5588)
			(stroke
				(width 0.1)
				(type default)
			)
			(layer "F.SilkS")
		)
		(fp_line
			(start -1.143 -0.5588)
			(end -1.143 0.5588)
			(stroke
				(width 0.1)
				(type default)
			)
			(layer "F.SilkS")
		)
		(fp_rect
			(start 1.143 -0.5588)
			(end -1.143 0.5588)
			(stroke
				(width 0)
				(type default)
			)
			(fill no)
			(layer "F.CrtYd")
		)
		(fp_line
			(start 0.508 0.3048)
			(end 0.508 -0.3048)
			(stroke
				(width 0.1)
				(type default)
			)
			(layer "F.Fab")
		)
		(fp_line
			(start 0.508 -0.3048)
			(end -0.508 -0.3048)
			(stroke
				(width 0.1)
				(type default)
			)
			(layer "F.Fab")
		)
		(fp_line
			(start -0.508 0.3048)
			(end 0.508 0.3048)
			(stroke
				(width 0.1)
				(type default)
			)
			(layer "F.Fab")
		)
		(fp_line
			(start -0.508 -0.3048)
			(end -0.508 0.3048)
			(stroke
				(width 0.1)
				(type default)
			)
			(layer "F.Fab")
		)
		(pad "1" smd rect
			(at -0.5334 0 180)
			(size 0.7112 0.6096)
			(layers "F.Cu" "F.Mask" "F.Paste")
			(net "XP12R0V")
		)
		(pad "2" smd rect
			(at 0.5334 0 180)
			(size 0.7112 0.6096)
			(layers "F.Cu" "F.Mask" "F.Paste")
			(net "XP12R0V_A_FLTB")
		)
		(zone
			(layer "F.Cu")
			(hatch none 0.5)
			(connect_pads
				(clearance 0)
			)
			(min_thickness 0.25)
			(keepout
				(tracks allowed)
				(vias not_allowed)
				(pads allowed)
				(copperpour not_allowed)
				(footprints allowed)
			)
			(placement
				(enabled no)
				(sheetname "")
			)
			(fill
				(thermal_gap 0.5)
				(thermal_bridge_width 0.5)
				(island_removal_mode 0)
			)
			(polygon
				(pts
					(xy 145.7452 -98.933) (xy 145.8976 -98.933) (xy 145.8976 -99.5426) (xy 145.7452 -99.5426)
				)
			)
		)
	)
)
